# BASEBOARD_FAB2 (Tioga Pass) — schematic netlist excerpt (pin names and nets, part order shuffled) for the footprints in the layout excerpt that follows; sources: Cadence DE-HDL packaged netlist, KiCad conversion of Wiwynn_Tioga_Pass_MB.brd

R7E16  RES  1.37K 1% CHIP  pkg 0402  page 241 : A = VR_P5V_STBY_VSENSE ; B = AGND_P5V_STBY

Y9F2  OSC_C  24MHZ OSC  pkg SM4  page 145
  ENABLE_CONTROL  = PU_24M_OSC_OE
  GND  = GND
  \out\  = CLK_24M_BMC_CLKIN_R
  VDD  = P3V3_STBY

C3D22  CAP  10UF 16V 10% X7R  pkg 0805  page 102 : A = P3V3_DB1200 ; B = GND

(kicad_pcb
	(version 20260206)
	(generator "pcbnew")
	(generator_version "10.0")
	(general
		(thickness 1.6)
		(legacy_teardrops no)
	)
	(paper "A4")
	(title_block
		(title "Wiwynn_Tioga_Pass_MB.brd")
		(comment 1 "Tioga Pass / footprints 991-993 of 4770")
	)
	(layers
		(0 "F.Cu" signal "TOP")
		(4 "In1.Cu" signal "L2GND")
		(6 "In2.Cu" signal "L3")
		(8 "In3.Cu" signal "L4GND")
		(10 "In4.Cu" signal "L5")
		(12 "In5.Cu" signal "L6GND")
		(14 "In6.Cu" signal "L7VCC")
		(16 "In7.Cu" signal "L8VCC")
		(18 "In8.Cu" signal "L9GND")
		(20 "In9.Cu" signal "L10")
		(22 "In10.Cu" signal "L11GND")
		(24 "In11.Cu" signal "L12")
		(26 "In12.Cu" signal "L13GND")
		(2 "B.Cu" signal "BOTTOM")
		(9 "F.Adhes" user "F.Adhesive")
		(11 "B.Adhes" user "B.Adhesive")
		(13 "F.Paste" user "Package Geometry/Pastemask Top")
		(15 "B.Paste" user "Package Geometry/Pastemask Bottom")
		(5 "F.SilkS" user "Ref Des/Silkscreen Top")
		(7 "B.SilkS" user "Ref Des/Silkscreen Bottom")
		(1 "F.Mask" user "Board Geometry/Soldermask Top")
		(3 "B.Mask" user "Board Geometry/Soldermask Bottom")
		(17 "Dwgs.User" user "User.Drawings")
		(19 "Cmts.User" user "User.Comments")
		(21 "Eco1.User" user "User.Eco1")
		(23 "Eco2.User" user "User.Eco2")
		(25 "Edge.Cuts" user "Board Geometry/Outline")
		(27 "Margin" user)
		(31 "F.CrtYd" user "Package Geometry/Place Bound Top")
		(29 "B.CrtYd" user "Package Geometry/Place Bound Bottom")
		(35 "F.Fab" user "Ref Des/Assembly Top")
		(33 "B.Fab" user "Ref Des/Assembly Bottom")
	)
	(footprint ""
		(layer "F.Cu")
		(at 429.847248 -48.813466)
		(property "Reference" "Y9F2"
			(at 4.41071 2.95656 90)
			(unlocked yes)
			(layer "F.SilkS")
			(effects
				(font
					(size 0.7874 0.5842)
					(thickness 0.1524)
				)
				(justify left)
			)
		)
		(property "Value" ""
			(at 0 0 0)
			(layer "F.Fab")
			(effects
				(font
					(size 1.27 1.27)
				)
			)
		)
		(duplicate_pad_numbers_are_jumpers no)
		(fp_circle
			(center -1.088644 0.020066)
			(end -0.961644 0.020066)
			(stroke
				(width 0.254)
				(type default)
			)
			(fill no)
			(layer "F.SilkS")
		)
		(fp_rect
			(start -0.500126 2.750058)
			(end 2.100072 -0.54991)
			(stroke
				(width 0)
				(type default)
			)
			(fill no)
			(layer "F.CrtYd")
		)
		(fp_line
			(start -0.500126 -0.54991)
			(end 2.100072 -0.54991)
			(stroke
				(width 0.1)
				(type default)
			)
			(layer "F.Fab")
		)
		(fp_line
			(start -0.500126 2.750058)
			(end -0.500126 -0.54991)
			(stroke
				(width 0.1)
				(type default)
			)
			(layer "F.Fab")
		)
		(fp_line
			(start 2.100072 -0.54991)
			(end 2.100072 2.750058)
			(stroke
				(width 0.1)
				(type default)
			)
			(layer "F.Fab")
		)
		(fp_line
			(start 2.100072 2.750058)
			(end -0.500126 2.750058)
			(stroke
				(width 0.1)
				(type default)
			)
			(layer "F.Fab")
		)
		(fp_circle
			(center -1.218946 -0.125984)
			(end -1.091946 -0.125984)
			(stroke
				(width 0.254)
				(type default)
			)
			(fill no)
			(layer "F.Fab")
		)
		(pad "1" smd rect
			(at 0 0)
			(size 1.1938 1.397)
			(layers "F.Cu" "F.Mask" "F.Paste")
			(net "PU_24M_OSC_OE")
		)
		(pad "2" smd rect
			(at 0 2.199894)
			(size 1.1938 1.397)
			(layers "F.Cu" "F.Mask" "F.Paste")
			(net "GND")
		)
		(pad "3" smd rect
			(at 1.599946 2.199894)
			(size 1.1938 1.397)
			(layers "F.Cu" "F.Mask" "F.Paste")
			(net "CLK_24M_BMC_CLKIN_R")
		)
		(pad "4" smd rect
			(at 1.599946 0)
			(size 1.1938 1.397)
			(layers "F.Cu" "F.Mask" "F.Paste")
			(net "P3V3_STBY")
		)
	)
	(footprint ""
		(layer "F.Cu")
		(at 162.7886 -72.644 90)
		(property "Reference" "C3D22"
			(at 0 0 90)
			(layer "F.SilkS")
			(hide yes)
			(effects
				(font
					(size 1.27 1.27)
				)
			)
		)
		(property "Value" ""
			(at 0 0 90)
			(layer "F.Fab")
			(effects
				(font
					(size 1.27 1.27)
				)
			)
		)
		(duplicate_pad_numbers_are_jumpers no)
		(fp_poly
			(pts
				(xy -0.7239 -0.2159) (xy 0.7239 -0.2159) (xy 0.7239 1.9939) (xy -0.7239 1.9939)
			)
			(stroke
				(width 0)
				(type default)
			)
			(fill no)
			(layer "F.CrtYd")
		)
		(fp_line
			(start 0.7239 -0.2159)
			(end -0.7239 -0.2159)
			(stroke
				(width 0.1)
				(type default)
			)
			(layer "F.Fab")
		)
		(fp_line
			(start -0.7239 -0.2159)
			(end -0.7239 1.9939)
			(stroke
				(width 0.1)
				(type default)
			)
			(layer "F.Fab")
		)
		(fp_line
			(start 0.7239 1.9939)
			(end 0.7239 -0.2159)
			(stroke
				(width 0.1)
				(type default)
			)
			(layer "F.Fab")
		)
		(fp_line
			(start -0.7239 1.9939)
			(end 0.7239 1.9939)
			(stroke
				(width 0.1)
				(type default)
			)
			(layer "F.Fab")
		)
		(pad "1" smd rect
			(at 0 0 90)
			(size 1.27 1.016)
			(layers "F.Cu" "F.Mask" "F.Paste")
			(net "P3V3_DB1200")
		)
		(pad "2" smd rect
			(at 0 1.778 90)
			(size 1.27 1.016)
			(layers "F.Cu" "F.Mask" "F.Paste")
			(net "GND")
		)
		(zone
			(layer "F.Cu")
			(hatch none 0.5)
			(connect_pads
				(clearance 0)
			)
			(min_thickness 0.25)
			(keepout
				(tracks not_allowed)
				(vias allowed)
				(pads allowed)
				(copperpour not_allowed)
				(footprints allowed)
			)
			(placement
				(enabled no)
				(sheetname "")
			)
			(fill
				(thermal_gap 0.5)
				(thermal_bridge_width 0.5)
				(island_removal_mode 0)
			)
			(polygon
				(pts
					(xy 163.2966 -72.009) (xy 163.2966 -73.279) (xy 164.0586 -73.279) (xy 164.0586 -72.009)
				)
			)
		)
	)
	(footprint ""
		(layer "F.Cu")
		(at 391.16 -64.5795)
		(property "Reference" "R7E16"
			(at 0 0 0)
			(layer "F.SilkS")
			(hide yes)
			(effects
				(font
					(size 1.27 1.27)
				)
			)
		)
		(property "Value" ""
			(at 0 0 0)
			(layer "F.Fab")
			(effects
				(font
					(size 1.27 1.27)
				)
			)
		)
		(duplicate_pad_numbers_are_jumpers no)
		(fp_poly
			(pts
				(xy -0.2794 -0.1016) (xy 0.2794 -0.1016) (xy 0.2794 0.9906) (xy -0.2794 0.9906)
			)
			(stroke
				(width 0)
				(type default)
			)
			(fill no)
			(layer "F.CrtYd")
		)
		(fp_line
			(start -0.2794 -0.1016)
			(end -0.2794 0.9906)
			(stroke
				(width 0.1)
				(type default)
			)
			(layer "F.Fab")
		)
		(fp_line
			(start -0.2794 0.9906)
			(end 0.2794 0.9906)
			(stroke
				(width 0.1)
				(type default)
			)
			(layer "F.Fab")
		)
		(fp_line
			(start 0.2794 -0.1016)
			(end -0.2794 -0.1016)
			(stroke
				(width 0.1)
				(type default)
			)
			(layer "F.Fab")
		)
		(fp_line
			(start 0.2794 0.9906)
			(end 0.2794 -0.1016)
			(stroke
				(width 0.1)
				(type default)
			)
			(layer "F.Fab")
		)
		(pad "1" smd rect
			(at 0 0)
			(size 0.508 0.508)
			(layers "F.Cu" "F.Mask" "F.Paste")
			(net "VR_P5V_STBY_VSENSE")
		)
		(pad "2" smd rect
			(at 0 0.889)
			(size 0.508 0.508)
			(layers "F.Cu" "F.Mask" "F.Paste")
			(net "AGND_P5V_STBY")
		)
		(zone
			(layer "F.Cu")
			(hatch none 0.5)
			(connect_pads
				(clearance 0)
			)
			(min_thickness 0.25)
			(keepout
				(tracks allowed)
				(vias not_allowed)
				(pads allowed)
				(copperpour not_allowed)
				(footprints allowed)
			)
			(placement
				(enabled no)
				(sheetname "")
			)
			(fill
				(thermal_gap 0.5)
				(thermal_bridge_width 0.5)
				(island_removal_mode 0)
			)
			(polygon
				(pts
					(xy 390.906 -64.3255) (xy 391.414 -64.3255) (xy 391.414 -63.9445) (xy 390.906 -63.9445)
				)
			)
		)
		(zone
			(layer "F.Cu")
			(hatch none 0.5)
			(connect_pads
				(clearance 0)
			)
			(min_thickness 0.25)
			(keepout
				(tracks not_allowed)
				(vias allowed)
				(pads allowed)
				(copperpour not_allowed)
				(footprints allowed)
			)
			(placement
				(enabled no)
				(sheetname "")
			)
			(fill
				(thermal_gap 0.5)
				(thermal_bridge_width 0.5)
				(island_removal_mode 0)
			)
			(polygon
				(pts
					(xy 390.906 -63.9445) (xy 391.414 -63.9445) (xy 391.414 -64.3255) (xy 390.906 -64.3255)
				)
			)
		)
	)
)
